(kicad_pcb
	(version 20241229)
	(generator "pcbnew")
	(generator_version "9.0")
	(general
		(thickness 1.62)
		(legacy_teardrops no)
	)
	(paper "A4")
	(title_block
		(title "OCuLink to 10GbE adapter")
		(date "2026-02-23")
		(rev "1.1.0")
		(company "Antmicro Ltd")
		(comment 1 "www.antmicro.com")
		(comment 9 "footprint 265 of 510 (U9), pads 480-503 of 503")
	)
	(layers
		(0 "F.Cu" signal)
		(4 "In1.Cu" signal)
		(6 "In2.Cu" signal)
		(8 "In3.Cu" signal)
		(10 "In4.Cu" signal)
		(12 "In5.Cu" signal)
		(14 "In6.Cu" signal)
		(2 "B.Cu" signal)
		(9 "F.Adhes" user "F.Adhesive")
		(11 "B.Adhes" user "B.Adhesive")
		(13 "F.Paste" user)
		(15 "B.Paste" user)
		(5 "F.SilkS" user "F.Silkscreen")
		(7 "B.SilkS" user "B.Silkscreen")
		(1 "F.Mask" user)
		(3 "B.Mask" user)
		(17 "Dwgs.User" user "User.Drawings")
		(19 "Cmts.User" user "User.Comments")
		(21 "Eco1.User" user "User.Eco1")
		(23 "Eco2.User" user "User.Eco2")
		(25 "Edge.Cuts" user)
		(27 "Margin" user)
		(31 "F.CrtYd" user "F.Courtyard")
		(29 "B.CrtYd" user "B.Courtyard")
		(35 "F.Fab" user)
		(33 "B.Fab" user)
	)
	(footprint "antmicro-footprints:FCBGA-503_22x22mm_Layout21x24_P1mm"
		(locked yes)
		(layer "F.Cu")
		(at 84.975 100 180)
		(property "Reference" "U9"
			(at -11.275 11.4 0)
			(layer "F.SilkS")
			(effects
				(font
					(size 0.7 0.7)
					(thickness 0.15)
				)
				(justify right bottom)
			)
		)
		(property "Value" "EZX710AT2_S_LMR5"
			(at -11.4 12.5 0)
			(layer "F.Fab")
			(hide yes)
			(effects
				(font
					(size 0.7 0.7)
					(thickness 0.15)
				)
				(justify right top)
			)
		)
		(property "Datasheet" "https://www.google.com/url?sa=t&source=web&rct=j&opi=89978449&url=https://cdrdv2-public.intel.com/596333/596333_X710-TM4_Datasheet_v_2_4.pdf&ved=2ahUKEwiSuv20_sCOAxXVCRAIHdxGO_UQFnoECBEQAQ&usg=AOvVaw1CjGyrGWE8ZvOdw4VBsY6U"
			(at -16.625 -13.91 0)
			(layer "F.Fab")
			(hide yes)
			(effects
				(font
					(size 0.7 0.7)
					(thickness 0.15)
				)
				(justify right top)
			)
		)
		(property "Description" "Ethernet ICs Intel Ethernet Controller 10 Gigabit X7"
			(at -12.015 -0.89 0)
			(layer "F.Fab")
			(hide yes)
			(effects
				(font
					(size 0.7 0.7)
					(thickness 0.15)
				)
				(justify right top)
			)
		)
		(property "MPN" "EZX710AT2 S LMR5"
			(at 0 0 180)
			(unlocked yes)
			(layer "F.Fab")
			(hide yes)
			(effects
				(font
					(size 1 1)
					(thickness 0.15)
				)
			)
		)
		(property "Manufacturer" "Intel"
			(at 0 0 180)
			(unlocked yes)
			(layer "F.Fab")
			(hide yes)
			(effects
				(font
					(size 1 1)
					(thickness 0.15)
				)
			)
		)
		(property "Author" "Antmicro"
			(at 0 0 180)
			(unlocked yes)
			(layer "F.Fab")
			(hide yes)
			(effects
				(font
					(size 1 1)
					(thickness 0.15)
				)
			)
		)
		(property "License" "Apache-2.0"
			(at 0 0 180)
			(unlocked yes)
			(layer "F.Fab")
			(hide yes)
			(effects
				(font
					(size 1 1)
					(thickness 0.15)
				)
			)
		)
		(sheetname "/X710-AT2 power/")
		(sheetfile "x710-at2-power.kicad_sch")
		(attr smd)
		(pad "W37" smd circle
			(at 7.75 5.62 180)
			(size 0.5 0.5)
			(layers "F.Cu" "F.Mask" "F.Paste")
			(net 28 "GND")
			(pinfunction "VSSA")
			(pintype "passive")
		)
		(pad "W39" smd circle
			(at 8.75 5.62 180)
			(size 0.5 0.5)
			(layers "F.Cu" "F.Mask" "F.Paste")
			(net 28 "GND")
			(pinfunction "VSSA")
			(pintype "passive")
		)
		(pad "W41" smd circle
			(at 9.75 5.62 180)
			(size 0.5 0.5)
			(layers "F.Cu" "F.Mask" "F.Paste")
			(net 197 "unconnected-(U9D-GPIO_1-PadW41)")
			(pinfunction "GPIO_1")
			(pintype "passive+no_connect")
		)
		(pad "Y2" smd circle
			(at -9.75 6.485 180)
			(size 0.5 0.5)
			(layers "F.Cu" "F.Mask" "F.Paste")
			(net 28 "GND")
			(pinfunction "VSS_S")
			(pintype "power_in")
		)
		(pad "Y4" smd circle
			(at -8.75 6.485 180)
			(size 0.5 0.5)
			(layers "F.Cu" "F.Mask" "F.Paste")
			(net 28 "GND")
			(pinfunction "VSSA")
			(pintype "passive")
		)
		(pad "Y6" smd circle
			(at -7.75 6.485 180)
			(size 0.5 0.5)
			(layers "F.Cu" "F.Mask" "F.Paste")
			(net 28 "GND")
			(pinfunction "VSSA")
			(pintype "passive")
		)
		(pad "Y8" smd circle
			(at -6.75 6.485 180)
			(size 0.5 0.5)
			(layers "F.Cu" "F.Mask" "F.Paste")
			(net 28 "GND")
			(pinfunction "VSSA")
			(pintype "passive")
		)
		(pad "Y10" smd circle
			(at -5.75 6.485 180)
			(size 0.5 0.5)
			(layers "F.Cu" "F.Mask" "F.Paste")
			(net 3 "/X710-AT2 PCIe/RBIAS")
			(pinfunction "RBIAS")
			(pintype "passive")
		)
		(pad "Y12" smd circle
			(at -4.75 6.485 180)
			(size 0.5 0.5)
			(layers "F.Cu" "F.Mask" "F.Paste")
			(net 2 "/X710-AT2 PCIe/RSENSE")
			(pinfunction "RSENSE")
			(pintype "passive")
		)
		(pad "Y14" smd circle
			(at -3.75 6.485 180)
			(size 0.5 0.5)
			(layers "F.Cu" "F.Mask" "F.Paste")
			(net 28 "GND")
			(pinfunction "VSSA")
			(pintype "passive")
		)
		(pad "Y16" smd circle
			(at -2.75 6.485 180)
			(size 0.5 0.5)
			(layers "F.Cu" "F.Mask" "F.Paste")
			(net 121 "/X710-AT2 RSVD/DEBUG_Y16")
			(pinfunction "DEBUG_Y16")
			(pintype "passive")
		)
		(pad "Y18" smd circle
			(at -1.75 6.485 180)
			(size 0.5 0.5)
			(layers "F.Cu" "F.Mask" "F.Paste")
			(net 128 "/X710-AT2 RSVD/RSVDY18_VSS")
			(pinfunction "RSVDY18_VSS")
			(pintype "passive")
		)
		(pad "Y20" smd circle
			(at -0.75 6.485 180)
			(size 0.5 0.5)
			(layers "F.Cu" "F.Mask" "F.Paste")
			(net 119 "/X710-AT2 RSVD/DEBUG_Y20")
			(pinfunction "DEBUG_Y20")
			(pintype "passive")
		)
		(pad "Y22" smd circle
			(at 0.25 6.485 180)
			(size 0.5 0.5)
			(layers "F.Cu" "F.Mask" "F.Paste")
			(net 123 "/X710-AT2 RSVD/RSVDY22_VSS")
			(pinfunction "RSVDY22_VSS")
			(pintype "passive")
		)
		(pad "Y24" smd circle
			(at 1.25 6.485 180)
			(size 0.5 0.5)
			(layers "F.Cu" "F.Mask" "F.Paste")
			(net 122 "/X710-AT2 RSVD/RSVDY24_VSS")
			(pinfunction "RSVDY24_VSS")
			(pintype "passive")
		)
		(pad "Y26" smd circle
			(at 2.25 6.485 180)
			(size 0.5 0.5)
			(layers "F.Cu" "F.Mask" "F.Paste")
			(net 28 "GND")
			(pinfunction "VSSA")
			(pintype "passive")
		)
		(pad "Y28" smd circle
			(at 3.25 6.485 180)
			(size 0.5 0.5)
			(layers "F.Cu" "F.Mask" "F.Paste")
			(net 28 "GND")
			(pinfunction "VSSA")
			(pintype "passive")
		)
		(pad "Y30" smd circle
			(at 4.25 6.485 180)
			(size 0.5 0.5)
			(layers "F.Cu" "F.Mask" "F.Paste")
			(net 274 "unconnected-(U9A-PER_5_P-PadY30)")
			(pinfunction "PER_5_P")
			(pintype "input+no_connect")
		)
		(pad "Y32" smd circle
			(at 5.25 6.485 180)
			(size 0.5 0.5)
			(layers "F.Cu" "F.Mask" "F.Paste")
			(net 28 "GND")
			(pinfunction "VSSA")
			(pintype "passive")
		)
		(pad "Y34" smd circle
			(at 6.25 6.485 180)
			(size 0.5 0.5)
			(layers "F.Cu" "F.Mask" "F.Paste")
			(net 277 "unconnected-(U9A-PER_6_P-PadY34)")
			(pinfunction "PER_6_P")
			(pintype "input+no_connect")
		)
		(pad "Y36" smd circle
			(at 7.25 6.485 180)
			(size 0.5 0.5)
			(layers "F.Cu" "F.Mask" "F.Paste")
			(net 28 "GND")
			(pinfunction "VSSA")
			(pintype "passive")
		)
		(pad "Y38" smd circle
			(at 8.25 6.485 180)
			(size 0.5 0.5)
			(layers "F.Cu" "F.Mask" "F.Paste")
			(net 359 "unconnected-(U9A-PER_7_P-PadY38)")
			(pinfunction "PER_7_P")
			(pintype "input+no_connect")
		)
		(pad "Y40" smd circle
			(at 9.25 6.485 180)
			(size 0.5 0.5)
			(layers "F.Cu" "F.Mask" "F.Paste")
			(net 28 "GND")
			(pinfunction "VSSA")
			(pintype "passive")
		)
		(pad "Y42" smd circle
			(at 10.25 6.485 180)
			(size 0.5 0.5)
			(layers "F.Cu" "F.Mask" "F.Paste")
			(net 86 "/2xRJ45/~{P1_LINK_LESS_THAN_10G}")
			(pinfunction "GPIO_2")
			(pintype "tri_state")
		)
	)
)
